# BASEBOARD_FAB2 (Tioga Pass) — schematic netlist excerpt (pin names and nets, part order shuffled) for the footprints in the layout excerpt that follows; sources: Cadence DE-HDL packaged netlist, KiCad conversion of Wiwynn_Tioga_Pass_MB.brd

C5P27  CAP  47UF 4V 20% X6S  pkg 0805  page 42 : A = PVCCIN_CPU0 ; B = GND
C10W1  CAP  10UF 16V 10% X6S  pkg 0805  page 251 : A = P12V_PUMP ; B = GND
C7L1  CAP  100UF 4V 20% X5R  pkg 0805  page 228 : A = PVDDQ_KLM ; B = GND

(kicad_pcb
	(version 20260206)
	(generator "pcbnew")
	(generator_version "10.0")
	(general
		(thickness 1.6)
		(legacy_teardrops no)
	)
	(paper "A4")
	(title_block
		(title "Wiwynn_Tioga_Pass_MB.brd")
		(comment 1 "Tioga Pass / footprints 2367-2369 of 4770")
	)
	(layers
		(0 "F.Cu" signal "TOP")
		(4 "In1.Cu" signal "L2GND")
		(6 "In2.Cu" signal "L3")
		(8 "In3.Cu" signal "L4GND")
		(10 "In4.Cu" signal "L5")
		(12 "In5.Cu" signal "L6GND")
		(14 "In6.Cu" signal "L7VCC")
		(16 "In7.Cu" signal "L8VCC")
		(18 "In8.Cu" signal "L9GND")
		(20 "In9.Cu" signal "L10")
		(22 "In10.Cu" signal "L11GND")
		(24 "In11.Cu" signal "L12")
		(26 "In12.Cu" signal "L13GND")
		(2 "B.Cu" signal "BOTTOM")
		(9 "F.Adhes" user "F.Adhesive")
		(11 "B.Adhes" user "B.Adhesive")
		(13 "F.Paste" user "Package Geometry/Pastemask Top")
		(15 "B.Paste" user "Package Geometry/Pastemask Bottom")
		(5 "F.SilkS" user "Ref Des/Silkscreen Top")
		(7 "B.SilkS" user "Ref Des/Silkscreen Bottom")
		(1 "F.Mask" user "Board Geometry/Soldermask Top")
		(3 "B.Mask" user "Board Geometry/Soldermask Bottom")
		(17 "Dwgs.User" user "User.Drawings")
		(19 "Cmts.User" user "User.Comments")
		(21 "Eco1.User" user "User.Eco1")
		(23 "Eco2.User" user "User.Eco2")
		(25 "Edge.Cuts" user "Board Geometry/Outline")
		(27 "Margin" user)
		(31 "F.CrtYd" user "Package Geometry/Place Bound Top")
		(29 "B.CrtYd" user "Package Geometry/Place Bound Bottom")
		(35 "F.Fab" user "Ref Des/Assembly Top")
		(33 "B.Fab" user "Ref Des/Assembly Bottom")
	)
	(footprint ""
		(layer "B.Cu")
		(at 258.548886 -77.82814)
		(property "Reference" "C5P27"
			(at 0 0 0)
			(layer "B.SilkS")
			(hide yes)
			(effects
				(font
					(size 1.27 1.27)
				)
				(justify mirror)
			)
		)
		(property "Value" ""
			(at 0 0 0)
			(layer "B.Fab")
			(effects
				(font
					(size 1.27 1.27)
				)
				(justify mirror)
			)
		)
		(duplicate_pad_numbers_are_jumpers no)
		(fp_poly
			(pts
				(xy 0.7239 -0.2159) (xy -0.7239 -0.2159) (xy -0.7239 1.9939) (xy 0.7239 1.9939)
			)
			(stroke
				(width 0)
				(type default)
			)
			(fill no)
			(layer "B.CrtYd")
		)
		(fp_line
			(start -0.7239 -0.2159)
			(end 0.7239 -0.2159)
			(stroke
				(width 0.1)
				(type default)
			)
			(layer "B.Fab")
		)
		(fp_line
			(start -0.7239 1.9939)
			(end -0.7239 -0.2159)
			(stroke
				(width 0.1)
				(type default)
			)
			(layer "B.Fab")
		)
		(fp_line
			(start 0.7239 -0.2159)
			(end 0.7239 1.9939)
			(stroke
				(width 0.1)
				(type default)
			)
			(layer "B.Fab")
		)
		(fp_line
			(start 0.7239 1.9939)
			(end -0.7239 1.9939)
			(stroke
				(width 0.1)
				(type default)
			)
			(layer "B.Fab")
		)
		(pad "1" smd rect
			(at 0 0 180)
			(size 1.27 1.016)
			(layers "B.Cu" "B.Mask" "B.Paste")
			(net "PVCCIN_CPU0")
		)
		(pad "2" smd rect
			(at 0 1.778 180)
			(size 1.27 1.016)
			(layers "B.Cu" "B.Mask" "B.Paste")
			(net "GND")
		)
		(zone
			(layer "B.Cu")
			(hatch none 0.5)
			(connect_pads
				(clearance 0)
			)
			(min_thickness 0.25)
			(keepout
				(tracks not_allowed)
				(vias allowed)
				(pads allowed)
				(copperpour not_allowed)
				(footprints allowed)
			)
			(placement
				(enabled no)
				(sheetname "")
			)
			(fill
				(thermal_gap 0.5)
				(thermal_bridge_width 0.5)
				(island_removal_mode 0)
			)
			(polygon
				(pts
					(xy 259.183886 -77.32014) (xy 257.913886 -77.32014) (xy 257.913886 -76.55814) (xy 259.183886 -76.55814)
				)
			)
		)
	)
	(footprint ""
		(layer "B.Cu")
		(at 110.318296 -156.910024 -90)
		(property "Reference" "C7L1"
			(at 0 0 90)
			(layer "B.SilkS")
			(hide yes)
			(effects
				(font
					(size 1.27 1.27)
				)
				(justify mirror)
			)
		)
		(property "Value" ""
			(at 0 0 90)
			(layer "B.Fab")
			(effects
				(font
					(size 1.27 1.27)
				)
				(justify mirror)
			)
		)
		(duplicate_pad_numbers_are_jumpers no)
		(fp_poly
			(pts
				(xy 0.7239 -0.2159) (xy -0.7239 -0.2159) (xy -0.7239 1.9939) (xy 0.7239 1.9939)
			)
			(stroke
				(width 0)
				(type default)
			)
			(fill no)
			(layer "B.CrtYd")
		)
		(fp_line
			(start -0.7239 1.9939)
			(end -0.7239 -0.2159)
			(stroke
				(width 0.1)
				(type default)
			)
			(layer "B.Fab")
		)
		(fp_line
			(start 0.7239 1.9939)
			(end -0.7239 1.9939)
			(stroke
				(width 0.1)
				(type default)
			)
			(layer "B.Fab")
		)
		(fp_line
			(start -0.7239 -0.2159)
			(end 0.7239 -0.2159)
			(stroke
				(width 0.1)
				(type default)
			)
			(layer "B.Fab")
		)
		(fp_line
			(start 0.7239 -0.2159)
			(end 0.7239 1.9939)
			(stroke
				(width 0.1)
				(type default)
			)
			(layer "B.Fab")
		)
		(pad "1" smd rect
			(at 0 0 90)
			(size 1.27 1.016)
			(layers "B.Cu" "B.Mask" "B.Paste")
			(net "PVDDQ_KLM")
		)
		(pad "2" smd rect
			(at 0 1.778 90)
			(size 1.27 1.016)
			(layers "B.Cu" "B.Mask" "B.Paste")
			(net "GND")
		)
		(zone
			(layer "B.Cu")
			(hatch none 0.5)
			(connect_pads
				(clearance 0)
			)
			(min_thickness 0.25)
			(keepout
				(tracks not_allowed)
				(vias allowed)
				(pads allowed)
				(copperpour not_allowed)
				(footprints allowed)
			)
			(placement
				(enabled no)
				(sheetname "")
			)
			(fill
				(thermal_gap 0.5)
				(thermal_bridge_width 0.5)
				(island_removal_mode 0)
			)
			(polygon
				(pts
					(xy 109.810296 -156.275024) (xy 109.810296 -157.545024) (xy 109.048296 -157.545024) (xy 109.048296 -156.275024)
				)
			)
		)
	)
	(footprint ""
		(layer "B.Cu")
		(at 14.66723 -122.874278 180)
		(property "Reference" "C10W1"
			(at -1.47828 0.78994 270)
			(unlocked yes)
			(layer "B.SilkS")
			(effects
				(font
					(size 0.4064 0.254)
					(thickness 0.1524)
				)
				(justify mirror)
			)
		)
		(property "Value" ""
			(at 0 0 0)
			(layer "B.Fab")
			(effects
				(font
					(size 1.27 1.27)
				)
				(justify mirror)
			)
		)
		(duplicate_pad_numbers_are_jumpers no)
		(fp_poly
			(pts
				(xy 0.7239 -0.2159) (xy -0.7239 -0.2159) (xy -0.7239 1.9939) (xy 0.7239 1.9939)
			)
			(stroke
				(width 0)
				(type default)
			)
			(fill no)
			(layer "B.CrtYd")
		)
		(fp_line
			(start 0.7239 1.9939)
			(end -0.7239 1.9939)
			(stroke
				(width 0.1)
				(type default)
			)
			(layer "B.Fab")
		)
		(fp_line
			(start 0.7239 -0.2159)
			(end 0.7239 1.9939)
			(stroke
				(width 0.1)
				(type default)
			)
			(layer "B.Fab")
		)
		(fp_line
			(start -0.7239 1.9939)
			(end -0.7239 -0.2159)
			(stroke
				(width 0.1)
				(type default)
			)
			(layer "B.Fab")
		)
		(fp_line
			(start -0.7239 -0.2159)
			(end 0.7239 -0.2159)
			(stroke
				(width 0.1)
				(type default)
			)
			(layer "B.Fab")
		)
		(pad "1" smd rect
			(at 0 0)
			(size 1.27 1.016)
			(layers "B.Cu" "B.Mask" "B.Paste")
			(net "P12V_PUMP")
		)
		(pad "2" smd rect
			(at 0 1.778)
			(size 1.27 1.016)
			(layers "B.Cu" "B.Mask" "B.Paste")
			(net "GND")
		)
		(zone
			(layer "B.Cu")
			(hatch none 0.5)
			(connect_pads
				(clearance 0)
			)
			(min_thickness 0.25)
			(keepout
				(tracks not_allowed)
				(vias allowed)
				(pads allowed)
				(copperpour not_allowed)
				(footprints allowed)
			)
			(placement
				(enabled no)
				(sheetname "")
			)
			(fill
				(thermal_gap 0.5)
				(thermal_bridge_width 0.5)
				(island_removal_mode 0)
			)
			(polygon
				(pts
					(xy 14.03223 -123.382278) (xy 15.30223 -123.382278) (xy 15.30223 -124.144278) (xy 14.03223 -124.144278)
				)
			)
		)
	)
)
